# ZAIUS-MB-EVT3-HW-EBOM-X00_20161228-add_2nd_source_X15-20170106-Final.xls — POP_GA (bom)
| FOXCONN TECHNOLOGY GROUP |  |  |  |  |  |  |  |  |  |  |  |  |
| BILL OF MATERIAL |  |  |  |  |  |  |  |  |  |  |  |  |
| REV OF  BOM |  | CUSTOMER | <name> |  | CUSTOMER P/N |  | PRODUCT CODE |  | PWA  REV |  | DATE |  |
| Sourcing (Single/Sole/Multi) | Critical Commodity (Y or N) | Component Class (1, 2, other) | Customer PSL (Y or N) | Item Number | Foxconn P/N | Customer P/N | Part Description | Manufacturer  Full Name | Manufacturer  Part Number | Qty | RoHS Status | Location |
